(kicad_pcb
	(version 20260206)
	(generator "pcbnew")
	(generator_version "10.0")
	(general
		(thickness 1.6)
		(legacy_teardrops no)
	)
	(paper "A4")
	(title_block
		(title "panther-plus-userver — 13130-1b_20150205.brd")
		(comment 1 "Honey Badger (Wiwynn) / footprint 624 of 1509 (DIMM4), pads 163-169 of 210")
	)
	(layers
		(0 "F.Cu" signal "TOP")
		(4 "In1.Cu" signal "L2")
		(6 "In2.Cu" signal "L3")
		(8 "In3.Cu" signal "L4")
		(10 "In4.Cu" signal "L5")
		(12 "In5.Cu" signal "L6")
		(14 "In6.Cu" signal "L7")
		(16 "In7.Cu" signal "L8")
		(18 "In8.Cu" signal "L9")
		(20 "In9.Cu" signal "L10")
		(22 "In10.Cu" signal "L11")
		(2 "B.Cu" signal "BOTTOM")
		(9 "F.Adhes" user "F.Adhesive")
		(11 "B.Adhes" user "B.Adhesive")
		(13 "F.Paste" user "Package Geometry/Pastemask Top")
		(15 "B.Paste" user "Package Geometry/Pastemask Bottom")
		(5 "F.SilkS" user "Ref Des/Silkscreen Top")
		(7 "B.SilkS" user "Ref Des/Silkscreen Bottom")
		(1 "F.Mask" user "Board Geometry/Soldermask Top")
		(3 "B.Mask" user "Board Geometry/Soldermask Bottom")
		(17 "Dwgs.User" user "User.Drawings")
		(19 "Cmts.User" user "User.Comments")
		(21 "Eco1.User" user "User.Eco1")
		(23 "Eco2.User" user "User.Eco2")
		(25 "Edge.Cuts" user "Board Geometry/Outline")
		(27 "Margin" user)
		(31 "F.CrtYd" user "Package Geometry/Place Bound Top")
		(29 "B.CrtYd" user "Package Geometry/Place Bound Bottom")
		(35 "F.Fab" user "Ref Des/Assembly Top")
		(33 "B.Fab" user "Ref Des/Assembly Bottom")
	)
	(footprint ""
		(layer "F.Cu")
		(at 159.999934 -5.790692)
		(property "Reference" "DIMM4"
			(at 0 0 0)
			(layer "F.SilkS")
			(hide yes)
			(effects
				(font
					(size 1.27 1.27)
				)
			)
		)
		(property "Value" "DDR3-204P-174-COLAY-1-GP"
			(at -40.682164 -17.468088 0)
			(unlocked yes)
			(layer "F.Fab")
			(hide yes)
			(effects
				(font
					(size 1.016 1.016)
					(thickness 0.1524)
				)
			)
		)
		(property "Device Type" "AS0A626-H8SN-7H-COLAY-1"
			(at -40.682164 -18.992088 0)
			(unlocked yes)
			(layer "F.Fab")
			(hide yes)
			(effects
				(font
					(size 1.016 1.016)
					(thickness 0.1524)
				)
			)
		)
		(duplicate_pad_numbers_are_jumpers no)
		(pad "161" smd custom
			(at 18.750026 4.106672)
			(size 0.1143 0.1143)
			(layers "F.Cu" "F.Mask" "F.Paste")
			(net "M_B_DQ47")
			(options
				(clearance outline)
				(anchor circle)
			)
			(primitives
				(gr_poly
					(pts
						(xy 0 0.9017) (xy -0.03175 0.89916) (xy -0.0635 0.889) (xy -0.09144 0.87376) (xy -0.11684 0.85344)
						(xy -0.13716 0.82804) (xy -0.1524 0.8001) (xy -0.16256 0.76835) (xy -0.1651 0.7366) (xy -0.1651 -0.13462)
						(xy -0.17272 -0.14224) (xy -0.19812 -0.1778) (xy -0.2032 -0.18796) (xy -0.20701 -0.19685) (xy -0.21209 -0.20701)
						(xy -0.2159 -0.21717) (xy -0.21844 -0.22733) (xy -0.22225 -0.23876) (xy -0.22352 -0.24892) (xy -0.22606 -0.25908)
						(xy -0.22733 -0.27051) (xy -0.22733 -0.28067) (xy -0.2286 -0.2921) (xy -0.22733 -0.30353) (xy -0.22733 -0.31369)
						(xy -0.22606 -0.32512) (xy -0.22352 -0.33528) (xy -0.22225 -0.34544) (xy -0.21844 -0.35687) (xy -0.2159 -0.36703)
						(xy -0.21209 -0.37719) (xy -0.20701 -0.38735) (xy -0.2032 -0.39624) (xy -0.19812 -0.4064) (xy -0.17272 -0.44196)
						(xy -0.1651 -0.44958) (xy -0.1651 -0.7366) (xy -0.16256 -0.76835) (xy -0.1524 -0.8001) (xy -0.13716 -0.82804)
						(xy -0.11684 -0.85344) (xy -0.09144 -0.87376) (xy -0.0635 -0.889) (xy -0.03175 -0.89916) (xy 0 -0.9017)
						(xy 0.03175 -0.89916) (xy 0.0635 -0.889) (xy 0.09144 -0.87376) (xy 0.11684 -0.85344) (xy 0.13716 -0.82804)
						(xy 0.1524 -0.8001) (xy 0.16256 -0.76835) (xy 0.1651 -0.7366) (xy 0.1651 -0.44958) (xy 0.17272 -0.44196)
						(xy 0.19812 -0.4064) (xy 0.2032 -0.39624) (xy 0.20701 -0.38735) (xy 0.21209 -0.37719) (xy 0.2159 -0.36703)
						(xy 0.21844 -0.35687) (xy 0.22225 -0.34544) (xy 0.22352 -0.33528) (xy 0.22606 -0.32512) (xy 0.22733 -0.31369)
						(xy 0.22733 -0.30353) (xy 0.2286 -0.2921) (xy 0.22733 -0.28067) (xy 0.22733 -0.27051) (xy 0.22606 -0.25908)
						(xy 0.22352 -0.24892) (xy 0.22225 -0.23876) (xy 0.21844 -0.22733) (xy 0.2159 -0.21717) (xy 0.21209 -0.20701)
						(xy 0.20701 -0.19685) (xy 0.2032 -0.18796) (xy 0.19812 -0.1778) (xy 0.17272 -0.14224) (xy 0.1651 -0.13462)
						(xy 0.1651 0.7366) (xy 0.16256 0.76835) (xy 0.1524 0.8001) (xy 0.13716 0.82804) (xy 0.11684 0.85344)
						(xy 0.09144 0.87376) (xy 0.0635 0.889) (xy 0.03175 0.89916)
					)
					(width 0)
					(fill yes)
				)
			)
		)
		(pad "162" smd custom
			(at 19.05 -4.106672)
			(size 0.1143 0.1143)
			(layers "F.Cu" "F.Mask" "F.Paste")
			(net "M_B_DQ43")
			(options
				(clearance outline)
				(anchor circle)
			)
			(primitives
				(gr_poly
					(pts
						(xy 0 0.9017) (xy -0.03175 0.89916) (xy -0.0635 0.889) (xy -0.09144 0.87376) (xy -0.11684 0.85344)
						(xy -0.13716 0.82804) (xy -0.1524 0.8001) (xy -0.16256 0.76835) (xy -0.1651 0.7366) (xy -0.1651 0.44958)
						(xy -0.17272 0.44196) (xy -0.19812 0.4064) (xy -0.2032 0.39624) (xy -0.20701 0.38735) (xy -0.21209 0.37719)
						(xy -0.2159 0.36703) (xy -0.21844 0.35687) (xy -0.22225 0.34544) (xy -0.22352 0.33528) (xy -0.22606 0.32512)
						(xy -0.22733 0.31369) (xy -0.22733 0.30353) (xy -0.2286 0.2921) (xy -0.22733 0.28067) (xy -0.22733 0.27051)
						(xy -0.22606 0.25908) (xy -0.22352 0.24892) (xy -0.22225 0.23876) (xy -0.21844 0.22733) (xy -0.2159 0.21717)
						(xy -0.21209 0.20701) (xy -0.20701 0.19685) (xy -0.2032 0.18796) (xy -0.19812 0.1778) (xy -0.17272 0.14224)
						(xy -0.1651 0.13462) (xy -0.1651 -0.7366) (xy -0.16256 -0.76835) (xy -0.1524 -0.8001) (xy -0.13716 -0.82804)
						(xy -0.11684 -0.85344) (xy -0.09144 -0.87376) (xy -0.0635 -0.889) (xy -0.03175 -0.89916) (xy 0 -0.9017)
						(xy 0.03175 -0.89916) (xy 0.0635 -0.889) (xy 0.09144 -0.87376) (xy 0.11684 -0.85344) (xy 0.13716 -0.82804)
						(xy 0.1524 -0.8001) (xy 0.16256 -0.76835) (xy 0.1651 -0.7366) (xy 0.1651 0.13462) (xy 0.17272 0.14224)
						(xy 0.19812 0.1778) (xy 0.2032 0.18796) (xy 0.20701 0.19685) (xy 0.21209 0.20701) (xy 0.2159 0.21717)
						(xy 0.21844 0.22733) (xy 0.22225 0.23876) (xy 0.22352 0.24892) (xy 0.22606 0.25908) (xy 0.22733 0.27051)
						(xy 0.22733 0.28067) (xy 0.2286 0.2921) (xy 0.22733 0.30353) (xy 0.22733 0.31369) (xy 0.22606 0.32512)
						(xy 0.22352 0.33528) (xy 0.22225 0.34544) (xy 0.21844 0.35687) (xy 0.2159 0.36703) (xy 0.21209 0.37719)
						(xy 0.20701 0.38735) (xy 0.2032 0.39624) (xy 0.19812 0.4064) (xy 0.17272 0.44196) (xy 0.1651 0.44958)
						(xy 0.1651 0.7366) (xy 0.16256 0.76835) (xy 0.1524 0.8001) (xy 0.13716 0.82804) (xy 0.11684 0.85344)
						(xy 0.09144 0.87376) (xy 0.0635 0.889) (xy 0.03175 0.89916)
					)
					(width 0)
					(fill yes)
				)
			)
		)
		(pad "163" smd custom
			(at 19.349974 4.106672)
			(size 0.1143 0.1143)
			(layers "F.Cu" "F.Mask" "F.Paste")
			(net "GND")
			(options
				(clearance outline)
				(anchor circle)
			)
			(primitives
				(gr_poly
					(pts
						(xy 0 0.9017) (xy -0.03175 0.89916) (xy -0.0635 0.889) (xy -0.09144 0.87376) (xy -0.11684 0.85344)
						(xy -0.13716 0.82804) (xy -0.1524 0.8001) (xy -0.16256 0.76835) (xy -0.1651 0.7366) (xy -0.1651 0.11938)
						(xy -0.17272 0.11176) (xy -0.19812 0.0762) (xy -0.2032 0.06604) (xy -0.20701 0.05715) (xy -0.21209 0.04699)
						(xy -0.2159 0.03683) (xy -0.21844 0.02667) (xy -0.22225 0.01524) (xy -0.22352 0.00508) (xy -0.22606 -0.00508)
						(xy -0.22733 -0.01651) (xy -0.22733 -0.02667) (xy -0.2286 -0.0381) (xy -0.22733 -0.04953) (xy -0.22733 -0.05969)
						(xy -0.22606 -0.07112) (xy -0.22352 -0.08128) (xy -0.22225 -0.09144) (xy -0.21844 -0.10287) (xy -0.2159 -0.11303)
						(xy -0.21209 -0.12319) (xy -0.20701 -0.13335) (xy -0.2032 -0.14224) (xy -0.19812 -0.1524) (xy -0.17272 -0.18796)
						(xy -0.1651 -0.19558) (xy -0.1651 -0.7366) (xy -0.16256 -0.76835) (xy -0.1524 -0.8001) (xy -0.13716 -0.82804)
						(xy -0.11684 -0.85344) (xy -0.09144 -0.87376) (xy -0.0635 -0.889) (xy -0.03175 -0.89916) (xy 0 -0.9017)
						(xy 0.03175 -0.89916) (xy 0.0635 -0.889) (xy 0.09144 -0.87376) (xy 0.11684 -0.85344) (xy 0.13716 -0.82804)
						(xy 0.1524 -0.8001) (xy 0.16256 -0.76835) (xy 0.1651 -0.7366) (xy 0.1651 -0.19685) (xy 0.17272 -0.18923)
						(xy 0.17907 -0.18034) (xy 0.18669 -0.17145) (xy 0.19177 -0.16256) (xy 0.19812 -0.15367) (xy 0.20828 -0.13335)
						(xy 0.21971 -0.10287) (xy 0.22225 -0.09271) (xy 0.22479 -0.08128) (xy 0.22606 -0.07112) (xy 0.2286 -0.05969)
						(xy 0.2286 -0.01651) (xy 0.22606 -0.00508) (xy 0.22479 0.00508) (xy 0.22225 0.01651) (xy 0.21971 0.02667)
						(xy 0.20828 0.05715) (xy 0.19812 0.07747) (xy 0.19177 0.08636) (xy 0.18669 0.09525) (xy 0.17907 0.10414)
						(xy 0.17272 0.11303) (xy 0.1651 0.12065) (xy 0.1651 0.7366) (xy 0.16256 0.76835) (xy 0.1524 0.8001)
						(xy 0.13716 0.82804) (xy 0.11684 0.85344) (xy 0.09144 0.87376) (xy 0.0635 0.889) (xy 0.03175 0.89916)
					)
					(width 0)
					(fill yes)
				)
			)
		)
		(pad "164" smd custom
			(at 19.649948 -4.106672)
			(size 0.1143 0.1143)
			(layers "F.Cu" "F.Mask" "F.Paste")
			(net "GND")
			(options
				(clearance outline)
				(anchor circle)
			)
			(primitives
				(gr_poly
					(pts
						(xy 0 0.9017) (xy -0.03175 0.89916) (xy -0.0635 0.889) (xy -0.09144 0.87376) (xy -0.11684 0.85344)
						(xy -0.13716 0.82804) (xy -0.1524 0.8001) (xy -0.16256 0.76835) (xy -0.1651 0.7366) (xy -0.1651 0.19685)
						(xy -0.17272 0.18923) (xy -0.17907 0.18034) (xy -0.18669 0.17145) (xy -0.19177 0.16256) (xy -0.19812 0.15367)
						(xy -0.20828 0.13335) (xy -0.21971 0.10287) (xy -0.22225 0.09271) (xy -0.22479 0.08128) (xy -0.22606 0.07112)
						(xy -0.2286 0.05969) (xy -0.2286 0.01651) (xy -0.22606 0.00508) (xy -0.22479 -0.00508) (xy -0.22225 -0.01651)
						(xy -0.21971 -0.02667) (xy -0.20828 -0.05715) (xy -0.19812 -0.07747) (xy -0.19177 -0.08636) (xy -0.18669 -0.09525)
						(xy -0.17907 -0.10414) (xy -0.17272 -0.11303) (xy -0.1651 -0.12065) (xy -0.1651 -0.7366) (xy -0.16256 -0.76835)
						(xy -0.1524 -0.8001) (xy -0.13716 -0.82804) (xy -0.11684 -0.85344) (xy -0.09144 -0.87376) (xy -0.0635 -0.889)
						(xy -0.03175 -0.89916) (xy 0 -0.9017) (xy 0.03175 -0.89916) (xy 0.0635 -0.889) (xy 0.09144 -0.87376)
						(xy 0.11684 -0.85344) (xy 0.13716 -0.82804) (xy 0.1524 -0.8001) (xy 0.16256 -0.76835) (xy 0.1651 -0.7366)
						(xy 0.1651 -0.11938) (xy 0.17272 -0.11176) (xy 0.19812 -0.0762) (xy 0.2032 -0.06604) (xy 0.20701 -0.05715)
						(xy 0.21209 -0.04699) (xy 0.2159 -0.03683) (xy 0.21844 -0.02667) (xy 0.22225 -0.01524) (xy 0.22352 -0.00508)
						(xy 0.22606 0.00508) (xy 0.22733 0.01651) (xy 0.22733 0.02667) (xy 0.2286 0.0381) (xy 0.22733 0.04953)
						(xy 0.22733 0.05969) (xy 0.22606 0.07112) (xy 0.22352 0.08128) (xy 0.22225 0.09144) (xy 0.21844 0.10287)
						(xy 0.2159 0.11303) (xy 0.21209 0.12319) (xy 0.20701 0.13335) (xy 0.2032 0.14224) (xy 0.19812 0.1524)
						(xy 0.17272 0.18796) (xy 0.1651 0.19558) (xy 0.1651 0.7366) (xy 0.16256 0.76835) (xy 0.1524 0.8001)
						(xy 0.13716 0.82804) (xy 0.11684 0.85344) (xy 0.09144 0.87376) (xy 0.0635 0.889) (xy 0.03175 0.89916)
					)
					(width 0)
					(fill yes)
				)
			)
		)
		(pad "165" smd custom
			(at 19.949922 4.106672)
			(size 0.1143 0.1143)
			(layers "F.Cu" "F.Mask" "F.Paste")
			(net "M_B_DQ52")
			(options
				(clearance outline)
				(anchor circle)
			)
			(primitives
				(gr_poly
					(pts
						(xy 0 0.9017) (xy -0.03175 0.89916) (xy -0.0635 0.889) (xy -0.09144 0.87376) (xy -0.11684 0.85344)
						(xy -0.13716 0.82804) (xy -0.1524 0.8001) (xy -0.16256 0.76835) (xy -0.1651 0.7366) (xy -0.1651 -0.13462)
						(xy -0.17272 -0.14224) (xy -0.19812 -0.1778) (xy -0.2032 -0.18796) (xy -0.20701 -0.19685) (xy -0.21209 -0.20701)
						(xy -0.2159 -0.21717) (xy -0.21844 -0.22733) (xy -0.22225 -0.23876) (xy -0.22352 -0.24892) (xy -0.22606 -0.25908)
						(xy -0.22733 -0.27051) (xy -0.22733 -0.28067) (xy -0.2286 -0.2921) (xy -0.22733 -0.30353) (xy -0.22733 -0.31369)
						(xy -0.22606 -0.32512) (xy -0.22352 -0.33528) (xy -0.22225 -0.34544) (xy -0.21844 -0.35687) (xy -0.2159 -0.36703)
						(xy -0.21209 -0.37719) (xy -0.20701 -0.38735) (xy -0.2032 -0.39624) (xy -0.19812 -0.4064) (xy -0.17272 -0.44196)
						(xy -0.1651 -0.44958) (xy -0.1651 -0.7366) (xy -0.16256 -0.76835) (xy -0.1524 -0.8001) (xy -0.13716 -0.82804)
						(xy -0.11684 -0.85344) (xy -0.09144 -0.87376) (xy -0.0635 -0.889) (xy -0.03175 -0.89916) (xy 0 -0.9017)
						(xy 0.03175 -0.89916) (xy 0.0635 -0.889) (xy 0.09144 -0.87376) (xy 0.11684 -0.85344) (xy 0.13716 -0.82804)
						(xy 0.1524 -0.8001) (xy 0.16256 -0.76835) (xy 0.1651 -0.7366) (xy 0.1651 -0.44958) (xy 0.17272 -0.44196)
						(xy 0.19812 -0.4064) (xy 0.2032 -0.39624) (xy 0.20701 -0.38735) (xy 0.21209 -0.37719) (xy 0.2159 -0.36703)
						(xy 0.21844 -0.35687) (xy 0.22225 -0.34544) (xy 0.22352 -0.33528) (xy 0.22606 -0.32512) (xy 0.22733 -0.31369)
						(xy 0.22733 -0.30353) (xy 0.2286 -0.2921) (xy 0.22733 -0.28067) (xy 0.22733 -0.27051) (xy 0.22606 -0.25908)
						(xy 0.22352 -0.24892) (xy 0.22225 -0.23876) (xy 0.21844 -0.22733) (xy 0.2159 -0.21717) (xy 0.21209 -0.20701)
						(xy 0.20701 -0.19685) (xy 0.2032 -0.18796) (xy 0.19812 -0.1778) (xy 0.17272 -0.14224) (xy 0.1651 -0.13462)
						(xy 0.1651 0.7366) (xy 0.16256 0.76835) (xy 0.1524 0.8001) (xy 0.13716 0.82804) (xy 0.11684 0.85344)
						(xy 0.09144 0.87376) (xy 0.0635 0.889) (xy 0.03175 0.89916)
					)
					(width 0)
					(fill yes)
				)
			)
		)
		(pad "166" smd custom
			(at 20.249896 -4.106672)
			(size 0.1143 0.1143)
			(layers "F.Cu" "F.Mask" "F.Paste")
			(net "M_B_DQ48")
			(options
				(clearance outline)
				(anchor circle)
			)
			(primitives
				(gr_poly
					(pts
						(xy 0 0.9017) (xy -0.03175 0.89916) (xy -0.0635 0.889) (xy -0.09144 0.87376) (xy -0.11684 0.85344)
						(xy -0.13716 0.82804) (xy -0.1524 0.8001) (xy -0.16256 0.76835) (xy -0.1651 0.7366) (xy -0.1651 0.44958)
						(xy -0.17272 0.44196) (xy -0.19812 0.4064) (xy -0.2032 0.39624) (xy -0.20701 0.38735) (xy -0.21209 0.37719)
						(xy -0.2159 0.36703) (xy -0.21844 0.35687) (xy -0.22225 0.34544) (xy -0.22352 0.33528) (xy -0.22606 0.32512)
						(xy -0.22733 0.31369) (xy -0.22733 0.30353) (xy -0.2286 0.2921) (xy -0.22733 0.28067) (xy -0.22733 0.27051)
						(xy -0.22606 0.25908) (xy -0.22352 0.24892) (xy -0.22225 0.23876) (xy -0.21844 0.22733) (xy -0.2159 0.21717)
						(xy -0.21209 0.20701) (xy -0.20701 0.19685) (xy -0.2032 0.18796) (xy -0.19812 0.1778) (xy -0.17272 0.14224)
						(xy -0.1651 0.13462) (xy -0.1651 -0.7366) (xy -0.16256 -0.76835) (xy -0.1524 -0.8001) (xy -0.13716 -0.82804)
						(xy -0.11684 -0.85344) (xy -0.09144 -0.87376) (xy -0.0635 -0.889) (xy -0.03175 -0.89916) (xy 0 -0.9017)
						(xy 0.03175 -0.89916) (xy 0.0635 -0.889) (xy 0.09144 -0.87376) (xy 0.11684 -0.85344) (xy 0.13716 -0.82804)
						(xy 0.1524 -0.8001) (xy 0.16256 -0.76835) (xy 0.1651 -0.7366) (xy 0.1651 0.13462) (xy 0.17272 0.14224)
						(xy 0.19812 0.1778) (xy 0.2032 0.18796) (xy 0.20701 0.19685) (xy 0.21209 0.20701) (xy 0.2159 0.21717)
						(xy 0.21844 0.22733) (xy 0.22225 0.23876) (xy 0.22352 0.24892) (xy 0.22606 0.25908) (xy 0.22733 0.27051)
						(xy 0.22733 0.28067) (xy 0.2286 0.2921) (xy 0.22733 0.30353) (xy 0.22733 0.31369) (xy 0.22606 0.32512)
						(xy 0.22352 0.33528) (xy 0.22225 0.34544) (xy 0.21844 0.35687) (xy 0.2159 0.36703) (xy 0.21209 0.37719)
						(xy 0.20701 0.38735) (xy 0.2032 0.39624) (xy 0.19812 0.4064) (xy 0.17272 0.44196) (xy 0.1651 0.44958)
						(xy 0.1651 0.7366) (xy 0.16256 0.76835) (xy 0.1524 0.8001) (xy 0.13716 0.82804) (xy 0.11684 0.85344)
						(xy 0.09144 0.87376) (xy 0.0635 0.889) (xy 0.03175 0.89916)
					)
					(width 0)
					(fill yes)
				)
			)
		)
		(pad "167" smd custom
			(at 20.550124 4.106672)
			(size 0.1143 0.1143)
			(layers "F.Cu" "F.Mask" "F.Paste")
			(net "M_B_DQ53")
			(options
				(clearance outline)
				(anchor circle)
			)
			(primitives
				(gr_poly
					(pts
						(xy 0 0.9017) (xy -0.03175 0.89916) (xy -0.0635 0.889) (xy -0.09144 0.87376) (xy -0.11684 0.85344)
						(xy -0.13716 0.82804) (xy -0.1524 0.8001) (xy -0.16256 0.76835) (xy -0.1651 0.7366) (xy -0.1651 0.11938)
						(xy -0.17272 0.11176) (xy -0.19812 0.0762) (xy -0.2032 0.06604) (xy -0.20701 0.05715) (xy -0.21209 0.04699)
						(xy -0.2159 0.03683) (xy -0.21844 0.02667) (xy -0.22225 0.01524) (xy -0.22352 0.00508) (xy -0.22606 -0.00508)
						(xy -0.22733 -0.01651) (xy -0.22733 -0.02667) (xy -0.2286 -0.0381) (xy -0.22733 -0.04953) (xy -0.22733 -0.05969)
						(xy -0.22606 -0.07112) (xy -0.22352 -0.08128) (xy -0.22225 -0.09144) (xy -0.21844 -0.10287) (xy -0.2159 -0.11303)
						(xy -0.21209 -0.12319) (xy -0.20701 -0.13335) (xy -0.2032 -0.14224) (xy -0.19812 -0.1524) (xy -0.17272 -0.18796)
						(xy -0.1651 -0.19558) (xy -0.1651 -0.7366) (xy -0.16256 -0.76835) (xy -0.1524 -0.8001) (xy -0.13716 -0.82804)
						(xy -0.11684 -0.85344) (xy -0.09144 -0.87376) (xy -0.0635 -0.889) (xy -0.03175 -0.89916) (xy 0 -0.9017)
						(xy 0.03175 -0.89916) (xy 0.0635 -0.889) (xy 0.09144 -0.87376) (xy 0.11684 -0.85344) (xy 0.13716 -0.82804)
						(xy 0.1524 -0.8001) (xy 0.16256 -0.76835) (xy 0.1651 -0.7366) (xy 0.1651 -0.19685) (xy 0.17272 -0.18923)
						(xy 0.17907 -0.18034) (xy 0.18669 -0.17145) (xy 0.19177 -0.16256) (xy 0.19812 -0.15367) (xy 0.20828 -0.13335)
						(xy 0.21971 -0.10287) (xy 0.22225 -0.09271) (xy 0.22479 -0.08128) (xy 0.22606 -0.07112) (xy 0.2286 -0.05969)
						(xy 0.2286 -0.01651) (xy 0.22606 -0.00508) (xy 0.22479 0.00508) (xy 0.22225 0.01651) (xy 0.21971 0.02667)
						(xy 0.20828 0.05715) (xy 0.19812 0.07747) (xy 0.19177 0.08636) (xy 0.18669 0.09525) (xy 0.17907 0.10414)
						(xy 0.17272 0.11303) (xy 0.1651 0.12065) (xy 0.1651 0.7366) (xy 0.16256 0.76835) (xy 0.1524 0.8001)
						(xy 0.13716 0.82804) (xy 0.11684 0.85344) (xy 0.09144 0.87376) (xy 0.0635 0.889) (xy 0.03175 0.89916)
					)
					(width 0)
					(fill yes)
				)
			)
		)
	)
)
